(kicad_pcb
	(version 20260206)
	(generator "pcbnew")
	(generator_version "10.0")
	(general
		(thickness 1.6)
		(legacy_teardrops no)
	)
	(paper "A4")
	(title_block
		(title "Wiwynn_Tioga_Pass_MB.brd")
		(comment 1 "Tioga Pass / footprints 2889-2896 of 4770")
	)
	(layers
		(0 "F.Cu" signal "TOP")
		(4 "In1.Cu" signal "L2GND")
		(6 "In2.Cu" signal "L3")
		(8 "In3.Cu" signal "L4GND")
		(10 "In4.Cu" signal "L5")
		(12 "In5.Cu" signal "L6GND")
		(14 "In6.Cu" signal "L7VCC")
		(16 "In7.Cu" signal "L8VCC")
		(18 "In8.Cu" signal "L9GND")
		(20 "In9.Cu" signal "L10")
		(22 "In10.Cu" signal "L11GND")
		(24 "In11.Cu" signal "L12")
		(26 "In12.Cu" signal "L13GND")
		(2 "B.Cu" signal "BOTTOM")
		(9 "F.Adhes" user "F.Adhesive")
		(11 "B.Adhes" user "B.Adhesive")
		(13 "F.Paste" user "Package Geometry/Pastemask Top")
		(15 "B.Paste" user "Package Geometry/Pastemask Bottom")
		(5 "F.SilkS" user "Ref Des/Silkscreen Top")
		(7 "B.SilkS" user "Ref Des/Silkscreen Bottom")
		(1 "F.Mask" user "Board Geometry/Soldermask Top")
		(3 "B.Mask" user "Board Geometry/Soldermask Bottom")
		(17 "Dwgs.User" user "User.Drawings")
		(19 "Cmts.User" user "User.Comments")
		(21 "Eco1.User" user "User.Eco1")
		(23 "Eco2.User" user "User.Eco2")
		(25 "Edge.Cuts" user "Board Geometry/Outline")
		(27 "Margin" user)
		(31 "F.CrtYd" user "Package Geometry/Place Bound Top")
		(29 "B.CrtYd" user "Package Geometry/Place Bound Bottom")
		(35 "F.Fab" user "Ref Des/Assembly Top")
		(33 "B.Fab" user "Ref Des/Assembly Bottom")
	)
	(footprint ""
		(layer "B.Cu")
		(at 374.8278 -102.0826 90)
		(property "Reference" "R3N3"
			(at 0 0 90)
			(layer "B.SilkS")
			(hide yes)
			(effects
				(font
					(size 1.27 1.27)
				)
				(justify mirror)
			)
		)
		(property "Value" ""
			(at 0 0 90)
			(layer "B.Fab")
			(effects
				(font
					(size 1.27 1.27)
				)
				(justify mirror)
			)
		)
		(duplicate_pad_numbers_are_jumpers no)
		(fp_poly
			(pts
				(xy 0.2794 -0.1016) (xy -0.2794 -0.1016) (xy -0.2794 0.9906) (xy 0.2794 0.9906)
			)
			(stroke
				(width 0)
				(type default)
			)
			(fill no)
			(layer "B.CrtYd")
		)
		(fp_line
			(start 0.2794 -0.1016)
			(end 0.2794 0.9906)
			(stroke
				(width 0.1)
				(type default)
			)
			(layer "B.Fab")
		)
		(fp_line
			(start -0.2794 -0.1016)
			(end 0.2794 -0.1016)
			(stroke
				(width 0.1)
				(type default)
			)
			(layer "B.Fab")
		)
		(fp_line
			(start 0.2794 0.9906)
			(end -0.2794 0.9906)
			(stroke
				(width 0.1)
				(type default)
			)
			(layer "B.Fab")
		)
		(fp_line
			(start -0.2794 0.9906)
			(end -0.2794 -0.1016)
			(stroke
				(width 0.1)
				(type default)
			)
			(layer "B.Fab")
		)
		(pad "1" smd rect
			(at 0 0 270)
			(size 0.508 0.508)
			(layers "B.Cu" "B.Mask" "B.Paste")
			(net "GND")
		)
		(pad "2" smd rect
			(at 0 0.889 270)
			(size 0.508 0.508)
			(layers "B.Cu" "B.Mask" "B.Paste")
			(net "PWRGD_PCH_PWROK")
		)
		(zone
			(layer "B.Cu")
			(hatch none 0.5)
			(connect_pads
				(clearance 0)
			)
			(min_thickness 0.25)
			(keepout
				(tracks allowed)
				(vias not_allowed)
				(pads allowed)
				(copperpour not_allowed)
				(footprints allowed)
			)
			(placement
				(enabled no)
				(sheetname "")
			)
			(fill
				(thermal_gap 0.5)
				(thermal_bridge_width 0.5)
				(island_removal_mode 0)
			)
			(polygon
				(pts
					(xy 375.0818 -102.3366) (xy 375.0818 -101.8286) (xy 375.4628 -101.8286) (xy 375.4628 -102.3366)
				)
			)
		)
		(zone
			(layer "B.Cu")
			(hatch none 0.5)
			(connect_pads
				(clearance 0)
			)
			(min_thickness 0.25)
			(keepout
				(tracks not_allowed)
				(vias allowed)
				(pads allowed)
				(copperpour not_allowed)
				(footprints allowed)
			)
			(placement
				(enabled no)
				(sheetname "")
			)
			(fill
				(thermal_gap 0.5)
				(thermal_bridge_width 0.5)
				(island_removal_mode 0)
			)
			(polygon
				(pts
					(xy 375.4628 -102.3366) (xy 375.4628 -101.8286) (xy 375.0818 -101.8286) (xy 375.0818 -102.3366)
				)
			)
		)
	)
	(footprint ""
		(layer "B.Cu")
		(at 368.7064 -5.3467 180)
		(property "Reference" "R3T14"
			(at 0 0 0)
			(layer "B.SilkS")
			(hide yes)
			(effects
				(font
					(size 1.27 1.27)
				)
				(justify mirror)
			)
		)
		(property "Value" ""
			(at 0 0 0)
			(layer "B.Fab")
			(effects
				(font
					(size 1.27 1.27)
				)
				(justify mirror)
			)
		)
		(duplicate_pad_numbers_are_jumpers no)
		(fp_poly
			(pts
				(xy 0.2794 -0.1016) (xy -0.2794 -0.1016) (xy -0.2794 0.9906) (xy 0.2794 0.9906)
			)
			(stroke
				(width 0)
				(type default)
			)
			(fill no)
			(layer "B.CrtYd")
		)
		(fp_line
			(start 0.2794 0.9906)
			(end -0.2794 0.9906)
			(stroke
				(width 0.1)
				(type default)
			)
			(layer "B.Fab")
		)
		(fp_line
			(start 0.2794 -0.1016)
			(end 0.2794 0.9906)
			(stroke
				(width 0.1)
				(type default)
			)
			(layer "B.Fab")
		)
		(fp_line
			(start -0.2794 0.9906)
			(end -0.2794 -0.1016)
			(stroke
				(width 0.1)
				(type default)
			)
			(layer "B.Fab")
		)
		(fp_line
			(start -0.2794 -0.1016)
			(end 0.2794 -0.1016)
			(stroke
				(width 0.1)
				(type default)
			)
			(layer "B.Fab")
		)
		(pad "1" smd rect
			(at 0 0)
			(size 0.508 0.508)
			(layers "B.Cu" "B.Mask" "B.Paste")
			(net "FM_BIOS_USB_RECOVERY")
		)
		(pad "2" smd rect
			(at 0 0.889)
			(size 0.508 0.508)
			(layers "B.Cu" "B.Mask" "B.Paste")
			(net "GND")
		)
		(zone
			(layer "B.Cu")
			(hatch none 0.5)
			(connect_pads
				(clearance 0)
			)
			(min_thickness 0.25)
			(keepout
				(tracks not_allowed)
				(vias allowed)
				(pads allowed)
				(copperpour not_allowed)
				(footprints allowed)
			)
			(placement
				(enabled no)
				(sheetname "")
			)
			(fill
				(thermal_gap 0.5)
				(thermal_bridge_width 0.5)
				(island_removal_mode 0)
			)
			(polygon
				(pts
					(xy 368.4524 -5.9817) (xy 368.9604 -5.9817) (xy 368.9604 -5.6007) (xy 368.4524 -5.6007)
				)
			)
		)
		(zone
			(layer "B.Cu")
			(hatch none 0.5)
			(connect_pads
				(clearance 0)
			)
			(min_thickness 0.25)
			(keepout
				(tracks allowed)
				(vias not_allowed)
				(pads allowed)
				(copperpour not_allowed)
				(footprints allowed)
			)
			(placement
				(enabled no)
				(sheetname "")
			)
			(fill
				(thermal_gap 0.5)
				(thermal_bridge_width 0.5)
				(island_removal_mode 0)
			)
			(polygon
				(pts
					(xy 368.4524 -5.6007) (xy 368.9604 -5.6007) (xy 368.9604 -5.9817) (xy 368.4524 -5.9817)
				)
			)
		)
	)
	(footprint ""
		(layer "B.Cu")
		(at 347.316806 -61.257434)
		(property "Reference" "C2U13"
			(at 0 0 0)
			(layer "B.SilkS")
			(hide yes)
			(effects
				(font
					(size 1.27 1.27)
				)
				(justify mirror)
			)
		)
		(property "Value" ""
			(at 0 0 0)
			(layer "B.Fab")
			(effects
				(font
					(size 1.27 1.27)
				)
				(justify mirror)
			)
		)
		(duplicate_pad_numbers_are_jumpers no)
		(fp_poly
			(pts
				(xy -0.3048 -0.1016) (xy -0.3048 0.9906) (xy 0.3048 0.9906) (xy 0.3048 -0.1016)
			)
			(stroke
				(width 0)
				(type default)
			)
			(fill no)
			(layer "B.CrtYd")
		)
		(fp_line
			(start -0.3048 -0.1016)
			(end 0.3048 -0.1016)
			(stroke
				(width 0.1)
				(type default)
			)
			(layer "B.Fab")
		)
		(fp_line
			(start -0.3048 0.9906)
			(end -0.3048 -0.1016)
			(stroke
				(width 0.1)
				(type default)
			)
			(layer "B.Fab")
		)
		(fp_line
			(start 0.3048 -0.1016)
			(end 0.3048 0.9906)
			(stroke
				(width 0.1)
				(type default)
			)
			(layer "B.Fab")
		)
		(fp_line
			(start 0.3048 0.9906)
			(end -0.3048 0.9906)
			(stroke
				(width 0.1)
				(type default)
			)
			(layer "B.Fab")
		)
		(pad "1" smd rect
			(at 0 0 180)
			(size 0.508 0.508)
			(layers "B.Cu" "B.Mask" "B.Paste")
			(net "P3E_CPU0_PE1_PCH_RXP<5>")
		)
		(pad "2" smd rect
			(at 0 0.889 180)
			(size 0.508 0.508)
			(layers "B.Cu" "B.Mask" "B.Paste")
			(net "P3E_CPU0_PE1_SS_RXP<5>")
		)
		(zone
			(layer "B.Cu")
			(hatch none 0.5)
			(connect_pads
				(clearance 0)
			)
			(min_thickness 0.25)
			(keepout
				(tracks allowed)
				(vias not_allowed)
				(pads allowed)
				(copperpour not_allowed)
				(footprints allowed)
			)
			(placement
				(enabled no)
				(sheetname "")
			)
			(fill
				(thermal_gap 0.5)
				(thermal_bridge_width 0.5)
				(island_removal_mode 0)
			)
			(polygon
				(pts
					(xy 347.570806 -61.003434) (xy 347.062806 -61.003434) (xy 347.062806 -60.622434) (xy 347.570806 -60.622434)
				)
			)
		)
	)
	(footprint ""
		(layer "B.Cu")
		(at 375.285 -89.4715)
		(property "Reference" "R3N9"
			(at 0.8382 -0.67818 0)
			(unlocked yes)
			(layer "B.SilkS")
			(effects
				(font
					(size 0.4064 0.254)
					(thickness 0.1524)
				)
				(justify left mirror)
			)
		)
		(property "Value" ""
			(at 0 0 0)
			(layer "B.Fab")
			(effects
				(font
					(size 1.27 1.27)
				)
				(justify mirror)
			)
		)
		(duplicate_pad_numbers_are_jumpers no)
		(fp_poly
			(pts
				(xy 0.2794 -0.1016) (xy -0.2794 -0.1016) (xy -0.2794 0.9906) (xy 0.2794 0.9906)
			)
			(stroke
				(width 0)
				(type default)
			)
			(fill no)
			(layer "B.CrtYd")
		)
		(fp_line
			(start -0.2794 -0.1016)
			(end 0.2794 -0.1016)
			(stroke
				(width 0.1)
				(type default)
			)
			(layer "B.Fab")
		)
		(fp_line
			(start -0.2794 0.9906)
			(end -0.2794 -0.1016)
			(stroke
				(width 0.1)
				(type default)
			)
			(layer "B.Fab")
		)
		(fp_line
			(start 0.2794 -0.1016)
			(end 0.2794 0.9906)
			(stroke
				(width 0.1)
				(type default)
			)
			(layer "B.Fab")
		)
		(fp_line
			(start 0.2794 0.9906)
			(end -0.2794 0.9906)
			(stroke
				(width 0.1)
				(type default)
			)
			(layer "B.Fab")
		)
		(pad "1" smd rect
			(at 0 0 180)
			(size 0.508 0.508)
			(layers "B.Cu" "B.Mask" "B.Paste")
			(net "H_PM_SYNC1_GTL_R")
		)
		(pad "2" smd rect
			(at 0 0.889 180)
			(size 0.508 0.508)
			(layers "B.Cu" "B.Mask" "B.Paste")
			(net "H_PM_SYNC_GTL")
		)
		(zone
			(layer "B.Cu")
			(hatch none 0.5)
			(connect_pads
				(clearance 0)
			)
			(min_thickness 0.25)
			(keepout
				(tracks allowed)
				(vias not_allowed)
				(pads allowed)
				(copperpour not_allowed)
				(footprints allowed)
			)
			(placement
				(enabled no)
				(sheetname "")
			)
			(fill
				(thermal_gap 0.5)
				(thermal_bridge_width 0.5)
				(island_removal_mode 0)
			)
			(polygon
				(pts
					(xy 375.539 -89.2175) (xy 375.031 -89.2175) (xy 375.031 -88.8365) (xy 375.539 -88.8365)
				)
			)
		)
		(zone
			(layer "B.Cu")
			(hatch none 0.5)
			(connect_pads
				(clearance 0)
			)
			(min_thickness 0.25)
			(keepout
				(tracks not_allowed)
				(vias allowed)
				(pads allowed)
				(copperpour not_allowed)
				(footprints allowed)
			)
			(placement
				(enabled no)
				(sheetname "")
			)
			(fill
				(thermal_gap 0.5)
				(thermal_bridge_width 0.5)
				(island_removal_mode 0)
			)
			(polygon
				(pts
					(xy 375.539 -88.8365) (xy 375.031 -88.8365) (xy 375.031 -89.2175) (xy 375.539 -89.2175)
				)
			)
		)
	)
	(footprint ""
		(layer "B.Cu")
		(at 173.4947 -5.551424 -90)
		(property "Reference" "C6U11"
			(at 0 0 90)
			(layer "B.SilkS")
			(hide yes)
			(effects
				(font
					(size 1.27 1.27)
				)
				(justify mirror)
			)
		)
		(property "Value" ""
			(at 0 0 90)
			(layer "B.Fab")
			(effects
				(font
					(size 1.27 1.27)
				)
				(justify mirror)
			)
		)
		(duplicate_pad_numbers_are_jumpers no)
		(fp_poly
			(pts
				(xy 0.4953 -0.2032) (xy -0.4953 -0.2032) (xy -0.4953 1.6002) (xy 0.4953 1.6002)
			)
			(stroke
				(width 0)
				(type default)
			)
			(fill no)
			(layer "B.CrtYd")
		)
		(fp_line
			(start -0.4953 1.6002)
			(end 0.4953 1.6002)
			(stroke
				(width 0.1)
				(type default)
			)
			(layer "B.Fab")
		)
		(fp_line
			(start 0.4953 1.6002)
			(end 0.4953 -0.2032)
			(stroke
				(width 0.1)
				(type default)
			)
			(layer "B.Fab")
		)
		(fp_line
			(start -0.4953 -0.2032)
			(end -0.4953 1.6002)
			(stroke
				(width 0.1)
				(type default)
			)
			(layer "B.Fab")
		)
		(fp_line
			(start 0.4953 -0.2032)
			(end -0.4953 -0.2032)
			(stroke
				(width 0.1)
				(type default)
			)
			(layer "B.Fab")
		)
		(pad "1" smd rect
			(at 0 0 90)
			(size 0.762 0.889)
			(layers "B.Cu" "B.Mask" "B.Paste")
			(net "VSENSE_PVDDQ_GHJ_VTT")
		)
		(pad "2" smd rect
			(at 0 1.397 90)
			(size 0.762 0.889)
			(layers "B.Cu" "B.Mask" "B.Paste")
			(net "GND")
		)
		(zone
			(layer "B.Cu")
			(hatch none 0.5)
			(connect_pads
				(clearance 0)
			)
			(min_thickness 0.25)
			(keepout
				(tracks not_allowed)
				(vias allowed)
				(pads allowed)
				(copperpour not_allowed)
				(footprints allowed)
			)
			(placement
				(enabled no)
				(sheetname "")
			)
			(fill
				(thermal_gap 0.5)
				(thermal_bridge_width 0.5)
				(island_removal_mode 0)
			)
			(polygon
				(pts
					(xy 173.0502 -5.170424) (xy 173.0502 -5.932424) (xy 172.5422 -5.932424) (xy 172.5422 -5.170424)
				)
			)
		)
	)
	(footprint ""
		(layer "B.Cu")
		(at 488.191302 -48.124872 -90)
		(property "Reference" "C9E12"
			(at 0 0 90)
			(layer "B.SilkS")
			(hide yes)
			(effects
				(font
					(size 1.27 1.27)
				)
				(justify mirror)
			)
		)
		(property "Value" ""
			(at 0 0 90)
			(layer "B.Fab")
			(effects
				(font
					(size 1.27 1.27)
				)
				(justify mirror)
			)
		)
		(duplicate_pad_numbers_are_jumpers no)
		(fp_poly
			(pts
				(xy 0.4953 -0.2032) (xy -0.4953 -0.2032) (xy -0.4953 1.6002) (xy 0.4953 1.6002)
			)
			(stroke
				(width 0)
				(type default)
			)
			(fill no)
			(layer "B.CrtYd")
		)
		(fp_line
			(start -0.4953 1.6002)
			(end 0.4953 1.6002)
			(stroke
				(width 0.1)
				(type default)
			)
			(layer "B.Fab")
		)
		(fp_line
			(start 0.4953 1.6002)
			(end 0.4953 -0.2032)
			(stroke
				(width 0.1)
				(type default)
			)
			(layer "B.Fab")
		)
		(fp_line
			(start -0.4953 -0.2032)
			(end -0.4953 1.6002)
			(stroke
				(width 0.1)
				(type default)
			)
			(layer "B.Fab")
		)
		(fp_line
			(start 0.4953 -0.2032)
			(end -0.4953 -0.2032)
			(stroke
				(width 0.1)
				(type default)
			)
			(layer "B.Fab")
		)
		(pad "1" smd rect
			(at 0 0 90)
			(size 0.762 0.889)
			(layers "B.Cu" "B.Mask" "B.Paste")
			(net "P0V9_LAN")
		)
		(pad "2" smd rect
			(at 0 1.397 90)
			(size 0.762 0.889)
			(layers "B.Cu" "B.Mask" "B.Paste")
			(net "GND")
		)
		(zone
			(layer "B.Cu")
			(hatch none 0.5)
			(connect_pads
				(clearance 0)
			)
			(min_thickness 0.25)
			(keepout
				(tracks not_allowed)
				(vias allowed)
				(pads allowed)
				(copperpour not_allowed)
				(footprints allowed)
			)
			(placement
				(enabled no)
				(sheetname "")
			)
			(fill
				(thermal_gap 0.5)
				(thermal_bridge_width 0.5)
				(island_removal_mode 0)
			)
			(polygon
				(pts
					(xy 487.746802 -47.743872) (xy 487.746802 -48.505872) (xy 487.238802 -48.505872) (xy 487.238802 -47.743872)
				)
			)
		)
	)
	(footprint ""
		(layer "B.Cu")
		(at 347.17736 -77.788516)
		(property "Reference" "C3P22"
			(at 0 0 0)
			(layer "B.SilkS")
			(hide yes)
			(effects
				(font
					(size 1.27 1.27)
				)
				(justify mirror)
			)
		)
		(property "Value" ""
			(at 0 0 0)
			(layer "B.Fab")
			(effects
				(font
					(size 1.27 1.27)
				)
				(justify mirror)
			)
		)
		(duplicate_pad_numbers_are_jumpers no)
		(fp_poly
			(pts
				(xy -0.3048 -0.1016) (xy -0.3048 0.9906) (xy 0.3048 0.9906) (xy 0.3048 -0.1016)
			)
			(stroke
				(width 0)
				(type default)
			)
			(fill no)
			(layer "B.CrtYd")
		)
		(fp_line
			(start -0.3048 -0.1016)
			(end 0.3048 -0.1016)
			(stroke
				(width 0.1)
				(type default)
			)
			(layer "B.Fab")
		)
		(fp_line
			(start -0.3048 0.9906)
			(end -0.3048 -0.1016)
			(stroke
				(width 0.1)
				(type default)
			)
			(layer "B.Fab")
		)
		(fp_line
			(start 0.3048 -0.1016)
			(end 0.3048 0.9906)
			(stroke
				(width 0.1)
				(type default)
			)
			(layer "B.Fab")
		)
		(fp_line
			(start 0.3048 0.9906)
			(end -0.3048 0.9906)
			(stroke
				(width 0.1)
				(type default)
			)
			(layer "B.Fab")
		)
		(pad "1" smd rect
			(at 0 0 180)
			(size 0.508 0.508)
			(layers "B.Cu" "B.Mask" "B.Paste")
			(net "P3E_CPU0_PE1_SS_TXP<3>")
		)
		(pad "2" smd rect
			(at 0 0.889 180)
			(size 0.508 0.508)
			(layers "B.Cu" "B.Mask" "B.Paste")
			(net "P3E_CPU0_PE1_SS_C_TXP<3>")
		)
		(zone
			(layer "B.Cu")
			(hatch none 0.5)
			(connect_pads
				(clearance 0)
			)
			(min_thickness 0.25)
			(keepout
				(tracks allowed)
				(vias not_allowed)
				(pads allowed)
				(copperpour not_allowed)
				(footprints allowed)
			)
			(placement
				(enabled no)
				(sheetname "")
			)
			(fill
				(thermal_gap 0.5)
				(thermal_bridge_width 0.5)
				(island_removal_mode 0)
			)
			(polygon
				(pts
					(xy 347.43136 -77.534516) (xy 346.92336 -77.534516) (xy 346.92336 -77.153516) (xy 347.43136 -77.153516)
				)
			)
		)
		(zone
			(layer "B.Cu")
			(hatch none 0.5)
			(connect_pads
				(clearance 0)
			)
			(min_thickness 0.25)
			(keepout
				(tracks not_allowed)
				(vias allowed)
				(pads allowed)
				(copperpour not_allowed)
				(footprints allowed)
			)
			(placement
				(enabled no)
				(sheetname "")
			)
			(fill
				(thermal_gap 0.5)
				(thermal_bridge_width 0.5)
				(island_removal_mode 0)
			)
			(polygon
				(pts
					(xy 347.43136 -77.153516) (xy 346.92336 -77.153516) (xy 346.92336 -77.534516) (xy 347.43136 -77.534516)
				)
			)
		)
	)
	(footprint ""
		(layer "B.Cu")
		(at 480.00666 -27.70632 180)
		(property "Reference" "C2T19"
			(at 0 0 0)
			(layer "B.SilkS")
			(hide yes)
			(effects
				(font
					(size 1.27 1.27)
				)
				(justify mirror)
			)
		)
		(property "Value" ""
			(at 0 0 0)
			(layer "B.Fab")
			(effects
				(font
					(size 1.27 1.27)
				)
				(justify mirror)
			)
		)
		(duplicate_pad_numbers_are_jumpers no)
		(fp_poly
			(pts
				(xy -0.3048 -0.1016) (xy -0.3048 0.9906) (xy 0.3048 0.9906) (xy 0.3048 -0.1016)
			)
			(stroke
				(width 0)
				(type default)
			)
			(fill no)
			(layer "B.CrtYd")
		)
		(fp_line
			(start 0.3048 0.9906)
			(end -0.3048 0.9906)
			(stroke
				(width 0.1)
				(type default)
			)
			(layer "B.Fab")
		)
		(fp_line
			(start 0.3048 -0.1016)
			(end 0.3048 0.9906)
			(stroke
				(width 0.1)
				(type default)
			)
			(layer "B.Fab")
		)
		(fp_line
			(start -0.3048 0.9906)
			(end -0.3048 -0.1016)
			(stroke
				(width 0.1)
				(type default)
			)
			(layer "B.Fab")
		)
		(fp_line
			(start -0.3048 -0.1016)
			(end 0.3048 -0.1016)
			(stroke
				(width 0.1)
				(type default)
			)
			(layer "B.Fab")
		)
		(pad "1" smd rect
			(at 0 0)
			(size 0.508 0.508)
			(layers "B.Cu" "B.Mask" "B.Paste")
			(net "P3V3_STBY_MNG_CPU")
		)
		(pad "2" smd rect
			(at 0 0.889)
			(size 0.508 0.508)
			(layers "B.Cu" "B.Mask" "B.Paste")
			(net "GND")
		)
		(zone
			(layer "B.Cu")
			(hatch none 0.5)
			(connect_pads
				(clearance 0)
			)
			(min_thickness 0.25)
			(keepout
				(tracks not_allowed)
				(vias allowed)
				(pads allowed)
				(copperpour not_allowed)
				(footprints allowed)
			)
			(placement
				(enabled no)
				(sheetname "")
			)
			(fill
				(thermal_gap 0.5)
				(thermal_bridge_width 0.5)
				(island_removal_mode 0)
			)
			(polygon
				(pts
					(xy 479.75266 -28.34132) (xy 480.26066 -28.34132) (xy 480.26066 -27.96032) (xy 479.75266 -27.96032)
				)
			)
		)
		(zone
			(layer "B.Cu")
			(hatch none 0.5)
			(connect_pads
				(clearance 0)
			)
			(min_thickness 0.25)
			(keepout
				(tracks allowed)
				(vias not_allowed)
				(pads allowed)
				(copperpour not_allowed)
				(footprints allowed)
			)
			(placement
				(enabled no)
				(sheetname "")
			)
			(fill
				(thermal_gap 0.5)
				(thermal_bridge_width 0.5)
				(island_removal_mode 0)
			)
			(polygon
				(pts
					(xy 479.75266 -27.96032) (xy 480.26066 -27.96032) (xy 480.26066 -28.34132) (xy 479.75266 -28.34132)
				)
			)
		)
	)
)
